G04 ================== begin FILE IDENTIFICATION RECORD ==================*
G04 Layout Name:  D:/<user>/Wistron_project/16369-sd/gbr/16369-sd.brd*
G04 Film Name:    L4*
G04 File Format:  Gerber RS274X*
G04 File Origin:  Cadence Allegro 16.5-S056*
G04 Origin Date:  Wed Mar 29 13:12:56 2017*
G04 *
G04 Layer:  VIA CLASS/BOTTOM*
G04 Layer:  PIN/BOTTOM*
G04 Layer:  ETCH/BOTTOM*
G04 Layer:  DRAWING FORMAT/LAYER_PCB_STORY*
G04 Layer:  DRAWING FORMAT/LAYER_L4*
G04 *
G04 Offset:    (0.00 0.00)*
G04 Mirror:    No*
G04 Mode:      Positive*
G04 Rotation:  0*
G04 FullContactRelief:  No*
G04 UndefLineWidth:     6.00*
G04 ================== end FILE IDENTIFICATION RECORD ====================*
%FSLAX35Y35*MOIN*%
%IR0*IPPOS*OFA0.00000B0.00000*MIA0B0*SFA1.00000B1.00000*%
%ADD10C,.01*%
%ADD13C,.02*%
%ADD12C,.022*%
%ADD11C,.04*%
%ADD15C,.042*%
%ADD18C,.052*%
%ADD17C,.028*%
%ADD14C,.046*%
%ADD16C,.107*%
%ADD19C,.238*%
%ADD20C,.03*%
%ADD21C,.006*%
%ADD22C,.00675*%
%ADD31C,.05204*%
%ADD27C,.07004*%
%ADD26C,.04404*%
%ADD28C,.04604*%
%ADD25C,.09204*%
%ADD29C,.06604*%
%ADD30C,.07604*%
%ADD24C,.11004*%
%ADD32C,.13104*%
%ADD23C,.36204*%
G75*
%LPD*%
G75*
G36*
G01X54816Y38362D02*
X44838Y48340D01*
X44560D01*
X44500Y48400D01*
X43561D01*
X43560Y48402D01*
X42798D01*
X42180Y49020D01*
G02X42438Y49702I283J283D01*
G03X41401Y53910I-138J2198D01*
G01X41383Y53902D01*
X41252Y53870D01*
X41099Y53991D01*
X41100Y54089D01*
Y54100D01*
X37700Y57500D01*
Y64200D01*
X25200Y76700D01*
Y94650D01*
X24640Y95210D01*
Y98399D01*
G03X20891Y99973I-1547J1568D01*
G02X20208Y99692I-400J2D01*
G01X19642Y100258D01*
Y148464D01*
X25568Y154391D01*
Y169555D01*
G02X26103Y169931I400J-1D01*
G03Y176525I1180J3297D01*
G02X25568Y176901I-135J377D01*
G01Y179766D01*
X48155Y202355D01*
G02X48829Y202159I283J-283D01*
G03X51574Y204904I2247J498D01*
G02X51378Y205578I87J391D01*
G01X54002Y208202D01*
Y264781D01*
X48083Y270700D01*
X47601D01*
X47500Y270802D01*
X16962D01*
X16861Y270700D01*
X16600D01*
X13600Y267700D01*
Y235339D01*
X6061Y227800D01*
X3500D01*
X3001Y228299D01*
Y350394D01*
G02X3937Y351330I936J0D01*
G01X60630D01*
G02X61566Y350394I0J-936D01*
G01Y286302D01*
G03X64631Y280546I6938J0D01*
G01Y254887D01*
G03X61566Y249131I3873J-5757D01*
G01Y137457D01*
G03X63598Y132552I6938J1D01*
G01X92788Y103362D01*
G03X97693Y101330I4906J4906D01*
G01X134984D01*
G03X139889Y103362I-1J6938D01*
G01X155764Y119236D01*
X157200D01*
X161245Y115191D01*
Y113063D01*
X151837Y103655D01*
Y71332D01*
X153569Y69600D01*
X162200D01*
X164400Y71800D01*
Y75697D01*
X168850Y80147D01*
Y86350D01*
X171900Y89400D01*
Y90200D01*
X186302Y104602D01*
G03X186598Y104898I-1402J1698D01*
G01X187113Y105413D01*
Y107492D01*
X187108Y116716D01*
X187600Y117208D01*
Y159610D01*
X192022Y164032D01*
Y169503D01*
G02X192541Y169885I400J0D01*
G03Y176571I1042J3343D01*
G02X192022Y176953I-119J382D01*
G01Y178045D01*
X197777Y183800D01*
X205900D01*
X221800Y199700D01*
Y207998D01*
G02X222483Y208281I400J0D01*
G01X223492Y207272D01*
Y189712D01*
X220098Y186319D01*
Y182000D01*
G03X225502I2702J0D01*
G01Y184081D01*
X228894Y187474D01*
Y209510D01*
X225910Y212494D01*
G03X222432Y212784I-1910J-1910D01*
G02X221800Y213109I-232J326D01*
G01Y234300D01*
X209300Y246800D01*
Y260961D01*
X209304Y260981D01*
G03Y261853I-2158J436D01*
G01X209300Y261873D01*
Y274800D01*
X202296Y281804D01*
X177907D01*
X171111Y288600D01*
Y309535D01*
G02X171654Y309908I400J0D01*
G03Y316076I1181J3084D01*
G02X171111Y316449I-143J373D01*
G01Y350394D01*
G02X172047Y351330I936J0D01*
G01X228740D01*
G02X229676Y350394I0J-936D01*
G01Y215031D01*
G03X233513Y208826I6938J1D01*
G01X237033Y207066D01*
G02X237550Y206229I-419J-837D01*
G01Y187472D01*
G02X237033Y186635I-936J0D01*
G01X233513Y184875D01*
G03X229676Y178670I3101J-6206D01*
G01Y-22441D01*
G02X228740Y-23377I-936J0D01*
G01X204635D01*
Y-787D01*
G03X199666Y4182I-4970J-1D01*
G01X195093D01*
G02X194696Y4633I0J400D01*
G03X187156I-3770J485D01*
G02X186759Y4182I-397J-51D01*
G01X45919D01*
G02X45522Y4633I0J400D01*
G03X37982I-3770J485D01*
G02X37585Y4182I-397J-51D01*
G01X33011D01*
G03X28042Y-787I1J-4970D01*
G01Y-23377D01*
X3937D01*
G02X3001Y-22441I0J936D01*
G01Y63030D01*
X3050Y63050D01*
Y66304D01*
X5122Y68376D01*
X16124D01*
X22150Y62350D01*
Y49747D01*
X34400Y37497D01*
Y25000D01*
X35000Y24400D01*
Y18713D01*
G03Y16487I1900J-1113D01*
G01Y14200D01*
X36250Y12950D01*
X47182D01*
X47183Y12948D01*
X65152D01*
X66975Y11125D01*
X66999Y11089D01*
G03X67645Y10449I1839J1211D01*
G01X67663Y10437D01*
X68400Y9700D01*
X74700D01*
X76700Y11700D01*
Y13298D01*
X76900D01*
G03X76954Y17701I0J2202D01*
G01X76874Y17703D01*
X72200Y22378D01*
X58922D01*
X57715Y23585D01*
G02X57906Y24257I283J283D01*
G03X55551Y27596I-506J2143D01*
G02X54816Y27814I-335J218D01*
G01Y38362D01*
G37*
G36*
G01X19150Y202150D02*
X17738Y203562D01*
X17726Y203581D01*
G03X17021Y204286I-1869J-1164D01*
G01X17002Y204298D01*
X14870Y206430D01*
Y214526D01*
X17222Y216878D01*
X20099D01*
G02X20347Y216164I0J-400D01*
G03X28471I4062J-5141D01*
G02X28719Y216878I248J314D01*
G01X31577D01*
X32699Y218000D01*
X36000D01*
G03X36886Y217438I2189J2472D01*
G02X36925Y216723I-158J-367D01*
G03X40844Y217539I3231J-5700D01*
G02X40595Y218211I42J398D01*
G03X41375Y221339I-2406J2261D01*
G01X41345Y221451D01*
X43412Y223517D01*
Y231131D01*
X41233Y233310D01*
X40910D01*
G02X40616Y233981I0J400D01*
G03X39600Y239205I-2427J2239D01*
G01Y241109D01*
G03Y247079I-1411J2985D01*
G01Y248983D01*
G03X40595Y254229I-1411J2985D01*
G02X40844Y254901I291J274D01*
G03X36925Y255717I-688J6516D01*
G02X36886Y255002I-197J-348D01*
G03X35668Y254100I1304J-3034D01*
G01X16470D01*
X14870Y255700D01*
Y267010D01*
X17460Y269600D01*
X47002D01*
X52619Y263983D01*
Y208867D01*
X45902Y202150D01*
X19150D01*
G37*
G36*
G01X197360Y200400D02*
X174000D01*
X171300Y203100D01*
Y269243D01*
X178330Y276273D01*
X203867D01*
X206900Y273240D01*
Y273200D01*
X208000Y272100D01*
Y257000D01*
X204400Y253400D01*
X201619D01*
X201512Y253508D01*
X201349D01*
X201292Y253608D01*
G03X200832Y254229I-2865J-1641D01*
G02X201081Y254901I291J274D01*
G03X197162Y255717I-688J6516D01*
G02X197123Y255002I-197J-348D01*
G03X195451Y253400I1303J-3034D01*
G01X182600D01*
X180700Y251500D01*
Y220800D01*
X182700Y218800D01*
X195579D01*
G03X197123Y217438I2847J1672D01*
G02X197162Y216723I-158J-367D01*
G03X200462Y204471I3231J-5700D01*
G02X200749Y203789I4J-400D01*
G01X197360Y200400D01*
G37*
%LPC*%
G75*
G36*
G01X83774Y59260D02*
G02Y62340I-1574J1540D01*
G01X96238D01*
X100074Y58503D01*
X100154Y58501D01*
G02X97899Y56246I-54J-2201D01*
G01X97897Y56326D01*
X94962Y59260D01*
X83774D01*
G37*
G36*
G01X190846Y114401D02*
X190926Y114403D01*
X191960Y115438D01*
Y134261D01*
G02X195040I1540J1574D01*
G01Y114162D01*
X193103Y112226D01*
X193101Y112146D01*
G02X190846Y114401I-2201J54D01*
G37*
G36*
G01X46254Y108999D02*
X46174Y108997D01*
X45740Y108562D01*
Y101149D01*
X42440Y97849D01*
Y89974D01*
G02X39360I-1540J-1574D01*
G01Y99125D01*
X42660Y102425D01*
Y103772D01*
G03X42142Y104154I-400J0D01*
G02Y108362I-650J2104D01*
G03X42660Y108744I118J382D01*
G01Y109838D01*
X43997Y111174D01*
X43999Y111254D01*
G02X46254Y108999I2201J-54D01*
G37*
G36*
G01X88062Y24060D02*
X58726Y53397D01*
X58646Y53399D01*
G02X60901Y55654I54J2201D01*
G01X60903Y55574D01*
X89338Y27140D01*
X95484D01*
G03X95779Y27810I0J400D01*
G02X99417Y28417I1621J1490D01*
G03X99709Y27864I366J-160D01*
G02X97830Y24060I-409J-2164D01*
G01X88062D01*
G37*
G36*
G01X126146Y23800D02*
G02X123639Y24700I-1846J-1200D01*
G03X123854Y25300I-120J382D01*
G02X127274Y28040I1846J1200D01*
G01X130271D01*
G03X130629Y28618I0J400D01*
G02X133649Y31536I1971J982D01*
G03X134240Y31868I191J351D01*
G02X138013Y33300I2199J-107D01*
G01X150923D01*
X154562Y36940D01*
X165962D01*
X202222Y73200D01*
X202764D01*
X202821Y73255D01*
G02X203298Y69720I1519J-1595D01*
G01X203167Y69790D01*
X179003Y45626D01*
G03X179319Y44945I283J-283D01*
G02X180367Y40726I181J-2195D01*
G03X180304Y40024I157J-368D01*
G02X178226Y40209I-1211J-1839D01*
G03X178289Y40911I-157J368D01*
G02X177305Y42931I1211J1839D01*
G03X176624Y43247I-398J33D01*
G01X167238Y33860D01*
X155838D01*
X152199Y30222D01*
X138013D01*
G02X135390Y29825I-1574J1539D01*
G03X134799Y29493I-191J-351D01*
G02X134571Y28618I-2199J106D01*
G03X134929Y28040I358J-178D01*
G01X175762D01*
X206697Y58974D01*
X206699Y59054D01*
G02X208954Y56799I2201J-54D01*
G01X208874Y56797D01*
X177038Y24960D01*
X127274D01*
G02X126361Y24400I-1573J1541D01*
G03X126146Y23800I120J-382D01*
G37*
G36*
G01X136238Y11060D02*
X129162D01*
X126768Y13455D01*
X126688Y13457D01*
G02X128943Y15712I54J2201D01*
G01X128945Y15632D01*
X130438Y14140D01*
X134962D01*
X139200Y18378D01*
X212400D01*
X224960Y30938D01*
Y51429D01*
G03X224261Y51694I-400J0D01*
G02Y54606I-1652J1456D01*
G03X224960Y54871I299J265D01*
G01Y144062D01*
X220226Y148797D01*
X220146Y148799D01*
G02X222401Y151054I54J2201D01*
G01X222403Y150974D01*
X228040Y145338D01*
Y29662D01*
X213676Y15298D01*
X140476D01*
X136238Y11060D01*
G37*
G54D31*
X107506Y16719D03*
X116430Y16569D03*
X96200Y16400D03*
X133200Y17751D03*
G54D27*
X37283Y173228D03*
G54D26*
X43900Y59600D03*
X63300Y37300D03*
X40000Y77100D03*
X32200Y91400D03*
X33100Y73900D03*
X27200Y104100D03*
X24000Y120900D03*
X50400Y118300D03*
X51400Y168300D03*
X97500Y36600D03*
X73000Y57200D03*
X79604Y86869D03*
X79750Y76600D03*
X194560Y56777D03*
X211900Y24800D03*
X207293Y45526D03*
X188250Y66000D03*
X178843Y59000D03*
X163000Y43800D03*
X214800Y128309D03*
X192691Y84234D03*
X214500Y112000D03*
X218300Y32700D03*
X219000Y107560D03*
X218700Y132335D03*
G54D28*
X56400Y158800D03*
X44100Y154167D03*
X51500Y191500D03*
X55200Y285022D03*
X199600Y156500D03*
X220678Y284412D03*
G54D25*
X12000Y342400D03*
X180200Y342500D03*
X222000Y8200D03*
G54D29*
X51968Y312992D03*
X12598D03*
X212205D03*
G54D30*
X42126Y322835D03*
X32283D03*
X22440D03*
X42126Y303149D03*
X32283D03*
X22440D03*
X202363Y322835D03*
X192520D03*
X182677D03*
X202363Y303149D03*
X192520D03*
X182677D03*
G54D24*
X13800Y60400D03*
X218800Y337200D03*
G54D32*
X24409Y261417D03*
X184646D03*
Y211023D03*
G54D23*
X116339Y78740D03*
%LPD*%
G75*
G54D10*
X-18898Y16741D03*
X-17506Y723144D03*
X41752Y5118D03*
X13800Y60400D03*
X114497Y137176D03*
X115583Y329366D03*
X114497Y525759D03*
X115583Y717948D03*
X190926Y5118D03*
X218800Y337200D03*
X365520Y-1413D03*
X366606Y190776D03*
X365520Y387169D03*
X366606Y579359D03*
X494816Y713716D03*
G54D20*
G01X224000Y210584D02*
X226193Y208391D01*
Y188593D01*
X222800Y185200D01*
Y182000D01*
G54D11*
X-5631Y5915D03*
X-4866Y709193D03*
X12000Y342400D03*
X222000Y8200D03*
X180200Y342500D03*
X489553Y2518D03*
G54D21*
G01X-322688Y-405500D02*
X-321814Y-404625D01*
X-321159Y-403167D01*
X-320722Y-401124D01*
X-321159Y-399375D01*
X-322032Y-398208D01*
X-323561Y-397333D01*
X-329456D01*
Y-414833D01*
X-322251D01*
X-320722Y-413667D01*
X-319849Y-411916D01*
X-319412Y-409875D01*
X-319849Y-407833D01*
X-321159Y-406083D01*
X-322688Y-405500D01*
X-329456D01*
G01X-309991Y-414833D02*
Y-403167D01*
G01Y-405500D02*
X-308899Y-404333D01*
X-307807Y-403458D01*
X-306279Y-403167D01*
X-305188Y-403458D01*
X-303877Y-404333D01*
G01X-294019Y-420083D02*
X-292709Y-420666D01*
X-290962Y-420083D01*
X-289871Y-418917D01*
X-288997Y-417458D01*
X-287688Y-412792D01*
X-284849Y-403167D01*
G01X-291836D02*
X-287688Y-412792D01*
G01X-268441Y-404625D02*
X-269969Y-403458D01*
X-271279Y-403167D01*
X-273026Y-403750D01*
X-274336Y-404916D01*
X-275209Y-406958D01*
X-275428Y-409000D01*
X-275209Y-411042D01*
X-274336Y-412792D01*
X-273026Y-414250D01*
X-271279Y-414833D01*
X-269751Y-414250D01*
X-268441Y-413083D01*
G01X-257709Y-406958D02*
X-250722D01*
X-251377Y-404916D01*
X-252469Y-403750D01*
X-253997Y-403167D01*
X-255526Y-403458D01*
X-256836Y-404333D01*
X-257709Y-406375D01*
X-258146Y-408125D01*
Y-409875D01*
X-257709Y-411625D01*
X-256617Y-413375D01*
X-255307Y-414541D01*
X-253779Y-414833D01*
X-252251Y-414250D01*
X-250722Y-412500D01*
G01X-214631Y-398792D02*
X-215941Y-397916D01*
X-217469Y-397333D01*
X-219216D01*
X-221181Y-398208D01*
X-222709Y-399666D01*
X-223801Y-401417D01*
X-224674Y-404333D01*
X-224893Y-406958D01*
X-224456Y-409583D01*
X-223801Y-411333D01*
X-222491Y-413083D01*
X-220962Y-414250D01*
X-219434Y-414833D01*
X-217906D01*
X-216377Y-414250D01*
X-215067Y-413375D01*
X-213975Y-412209D01*
G01X-198004Y-414833D02*
Y-403167D01*
G01Y-405208D02*
X-198877Y-404042D01*
X-200188Y-403458D01*
X-201716Y-403167D01*
X-203244Y-403750D01*
X-204554Y-404916D01*
X-205428Y-406666D01*
X-205864Y-409000D01*
X-205428Y-411333D01*
X-204554Y-413083D01*
X-203244Y-414250D01*
X-201716Y-414833D01*
X-200188Y-414541D01*
X-198877Y-413667D01*
X-198004Y-412500D01*
G01X-188146Y-414833D02*
Y-403167D01*
G01Y-406083D02*
X-187272Y-404625D01*
X-185962Y-403458D01*
X-184216Y-403167D01*
X-182688Y-403458D01*
X-181377Y-404625D01*
X-180722Y-406666D01*
Y-414833D01*
G01X-171519Y-420083D02*
X-170209Y-420666D01*
X-168462Y-420083D01*
X-167371Y-418917D01*
X-166497Y-417458D01*
X-165188Y-412792D01*
X-162349Y-403167D01*
G01X-169336D02*
X-165188Y-412792D01*
G01X-149434Y-414833D02*
X-150744Y-414541D01*
X-152054Y-413375D01*
X-152928Y-411333D01*
X-153364Y-409000D01*
X-152928Y-406666D01*
X-152054Y-404625D01*
X-150744Y-403458D01*
X-149434Y-403167D01*
X-148124Y-403458D01*
X-146814Y-404625D01*
X-145941Y-406666D01*
X-145722Y-409000D01*
X-145941Y-411333D01*
X-146814Y-413375D01*
X-148124Y-414541D01*
X-149434Y-414833D01*
G01X-135646D02*
Y-403167D01*
G01Y-406083D02*
X-134772Y-404625D01*
X-133462Y-403458D01*
X-131716Y-403167D01*
X-130188Y-403458D01*
X-128877Y-404625D01*
X-128222Y-406666D01*
Y-414833D01*
G01X-101082D02*
Y-397333D01*
X-92786D01*
G01X-95842Y-405791D02*
X-101082D01*
G01X-82491Y-414833D02*
Y-403167D01*
G01Y-405500D02*
X-81399Y-404333D01*
X-80307Y-403458D01*
X-78779Y-403167D01*
X-77688Y-403458D01*
X-76377Y-404333D01*
G01X-61934Y-414833D02*
X-63244Y-414541D01*
X-64554Y-413375D01*
X-65428Y-411333D01*
X-65864Y-409000D01*
X-65428Y-406666D01*
X-64554Y-404625D01*
X-63244Y-403458D01*
X-61934Y-403167D01*
X-60624Y-403458D01*
X-59314Y-404625D01*
X-58441Y-406666D01*
X-58222Y-409000D01*
X-58441Y-411333D01*
X-59314Y-413375D01*
X-60624Y-414541D01*
X-61934Y-414833D01*
G01X-48146D02*
Y-403167D01*
G01Y-406083D02*
X-47272Y-404625D01*
X-45962Y-403458D01*
X-44216Y-403167D01*
X-42688Y-403458D01*
X-41377Y-404625D01*
X-40722Y-406666D01*
Y-414833D01*
G01X-26934Y-397333D02*
Y-414833D01*
G01X-29991Y-403167D02*
X-23877D01*
G01X3699Y-414833D02*
Y-397333D01*
X8939D01*
X10686Y-398208D01*
X11996Y-400250D01*
X12433Y-402583D01*
X11996Y-404916D01*
X10904Y-406666D01*
X8939Y-407542D01*
X3699D01*
G01X29496Y-414833D02*
Y-403167D01*
G01Y-405208D02*
X28623Y-404042D01*
X27312Y-403458D01*
X25784Y-403167D01*
X24256Y-403750D01*
X22946Y-404916D01*
X22072Y-406666D01*
X21636Y-409000D01*
X22072Y-411333D01*
X22946Y-413083D01*
X24256Y-414250D01*
X25784Y-414833D01*
X27312Y-414541D01*
X28623Y-413667D01*
X29496Y-412500D01*
G01X39354Y-414833D02*
Y-403167D01*
G01Y-406083D02*
X40228Y-404625D01*
X41538Y-403458D01*
X43284Y-403167D01*
X44812Y-403458D01*
X46123Y-404625D01*
X46778Y-406666D01*
Y-414833D01*
G01X57291Y-406958D02*
X64278D01*
X63623Y-404916D01*
X62531Y-403750D01*
X61003Y-403167D01*
X59474Y-403458D01*
X58164Y-404333D01*
X57291Y-406375D01*
X56854Y-408125D01*
Y-409875D01*
X57291Y-411625D01*
X58383Y-413375D01*
X59693Y-414541D01*
X61221Y-414833D01*
X62749Y-414250D01*
X64278Y-412500D01*
G01X78066Y-414833D02*
Y-397333D01*
G01X114812Y-405500D02*
X115686Y-404625D01*
X116341Y-403167D01*
X116778Y-401124D01*
X116341Y-399375D01*
X115468Y-398208D01*
X113939Y-397333D01*
X108044D01*
Y-414833D01*
X115249D01*
X116778Y-413667D01*
X117651Y-411916D01*
X118088Y-409875D01*
X117651Y-407833D01*
X116341Y-406083D01*
X114812Y-405500D01*
X108044D01*
G01X130566Y-414833D02*
X129256Y-414541D01*
X127946Y-413375D01*
X127072Y-411333D01*
X126636Y-409000D01*
X127072Y-406666D01*
X127946Y-404625D01*
X129256Y-403458D01*
X130566Y-403167D01*
X131876Y-403458D01*
X133186Y-404625D01*
X134059Y-406666D01*
X134278Y-409000D01*
X134059Y-411333D01*
X133186Y-413375D01*
X131876Y-414541D01*
X130566Y-414833D01*
G01X151996D02*
Y-403167D01*
G01Y-405208D02*
X151123Y-404042D01*
X149812Y-403458D01*
X148284Y-403167D01*
X146756Y-403750D01*
X145446Y-404916D01*
X144572Y-406666D01*
X144136Y-409000D01*
X144572Y-411333D01*
X145446Y-413083D01*
X146756Y-414250D01*
X148284Y-414833D01*
X149812Y-414541D01*
X151123Y-413667D01*
X151996Y-412500D01*
G01X162509Y-414833D02*
Y-403167D01*
G01Y-405500D02*
X163601Y-404333D01*
X164693Y-403458D01*
X166221Y-403167D01*
X167312Y-403458D01*
X168623Y-404333D01*
G01X186996Y-397333D02*
Y-414833D01*
G01Y-412209D02*
X186123Y-413667D01*
X184812Y-414541D01*
X183284Y-414833D01*
X181538Y-414250D01*
X180228Y-412792D01*
X179354Y-411042D01*
X179136Y-409000D01*
X179354Y-406958D01*
X180228Y-405208D01*
X181538Y-403750D01*
X183284Y-403167D01*
X184812Y-403458D01*
X185904Y-404042D01*
X186996Y-405208D01*
G01X-111361Y-369833D02*
Y-352333D01*
X-105684Y-366916D01*
X-100007Y-352333D01*
Y-369833D01*
G01X-88184D02*
X-89494Y-369541D01*
X-90804Y-368375D01*
X-91678Y-366333D01*
X-92114Y-364000D01*
X-91678Y-361666D01*
X-90804Y-359625D01*
X-89494Y-358458D01*
X-88184Y-358167D01*
X-86874Y-358458D01*
X-85564Y-359625D01*
X-84691Y-361666D01*
X-84472Y-364000D01*
X-84691Y-366333D01*
X-85564Y-368375D01*
X-86874Y-369541D01*
X-88184Y-369833D01*
G01X-66754Y-352333D02*
Y-369833D01*
G01Y-367209D02*
X-67627Y-368667D01*
X-68938Y-369541D01*
X-70466Y-369833D01*
X-72212Y-369250D01*
X-73522Y-367792D01*
X-74396Y-366042D01*
X-74614Y-364000D01*
X-74396Y-361958D01*
X-73522Y-360208D01*
X-72212Y-358750D01*
X-70466Y-358167D01*
X-68938Y-358458D01*
X-67846Y-359042D01*
X-66754Y-360208D01*
G01X-56459Y-361958D02*
X-49472D01*
X-50127Y-359916D01*
X-51219Y-358750D01*
X-52747Y-358167D01*
X-54276Y-358458D01*
X-55586Y-359333D01*
X-56459Y-361375D01*
X-56896Y-363125D01*
Y-364875D01*
X-56459Y-366625D01*
X-55367Y-368375D01*
X-54057Y-369541D01*
X-52529Y-369833D01*
X-51001Y-369250D01*
X-49472Y-367500D01*
G01X-35684Y-369833D02*
Y-352333D01*
G01X244916Y-414833D02*
Y-397333D01*
X242296Y-400833D01*
G01Y-414833D02*
X247536D01*
G01X258268Y-407542D02*
X259796Y-405500D01*
X261106Y-404333D01*
X262853Y-403750D01*
X264381Y-404333D01*
X265473Y-405500D01*
X266346Y-407250D01*
X266564Y-409291D01*
X266346Y-411042D01*
X265473Y-412792D01*
X264162Y-414250D01*
X262634Y-414833D01*
X260888Y-414250D01*
X259359Y-412500D01*
X258486Y-409875D01*
X258268Y-406958D01*
X258704Y-403167D01*
X259359Y-401124D01*
X260451Y-399083D01*
X261979Y-397625D01*
X263508Y-397333D01*
X265036Y-397916D01*
X266128Y-399375D01*
G01X275113Y-411333D02*
X276422Y-413375D01*
X278169Y-414541D01*
X280134Y-414833D01*
X281881Y-414541D01*
X283628Y-413083D01*
X284719Y-411333D01*
X284938Y-409583D01*
X284501Y-407542D01*
X282973Y-406083D01*
X281444Y-405500D01*
X279479D01*
G01X281444D02*
X282754Y-404625D01*
X283846Y-403167D01*
X284283Y-401417D01*
X283846Y-399666D01*
X282754Y-398208D01*
X280789Y-397333D01*
X278824Y-397625D01*
X276859Y-398792D01*
G01X293268Y-407542D02*
X294796Y-405500D01*
X296106Y-404333D01*
X297853Y-403750D01*
X299381Y-404333D01*
X300473Y-405500D01*
X301346Y-407250D01*
X301564Y-409291D01*
X301346Y-411042D01*
X300473Y-412792D01*
X299162Y-414250D01*
X297634Y-414833D01*
X295888Y-414250D01*
X294359Y-412500D01*
X293486Y-409875D01*
X293268Y-406958D01*
X293704Y-403167D01*
X294359Y-401124D01*
X295451Y-399083D01*
X296979Y-397625D01*
X298508Y-397333D01*
X300036Y-397916D01*
X301128Y-399375D01*
G01X311204Y-412792D02*
X312733Y-414250D01*
X314479Y-414833D01*
X316226Y-414250D01*
X317754Y-412500D01*
X318846Y-409875D01*
X319283Y-407250D01*
Y-404042D01*
X318846Y-401417D01*
X317754Y-399083D01*
X316444Y-397916D01*
X314916Y-397333D01*
X313169Y-397916D01*
X311859Y-399083D01*
X310986Y-400833D01*
X310549Y-403167D01*
X310986Y-405208D01*
X312078Y-407250D01*
X313388Y-408417D01*
X314916Y-408708D01*
X316662Y-408125D01*
X317973Y-406666D01*
X319283Y-404042D01*
G01X231799Y-369833D02*
Y-352333D01*
X237039D01*
X238786Y-353208D01*
X240096Y-355250D01*
X240533Y-357583D01*
X240096Y-359916D01*
X239004Y-361666D01*
X237039Y-362542D01*
X231799D01*
G01X258469Y-353792D02*
X257159Y-352916D01*
X255631Y-352333D01*
X253884D01*
X251919Y-353208D01*
X250391Y-354666D01*
X249299Y-356417D01*
X248426Y-359333D01*
X248207Y-361958D01*
X248644Y-364583D01*
X249299Y-366333D01*
X250609Y-368083D01*
X252138Y-369250D01*
X253666Y-369833D01*
X255194D01*
X256723Y-369250D01*
X258033Y-368375D01*
X259125Y-367209D01*
G01X272912Y-360500D02*
X273786Y-359625D01*
X274441Y-358167D01*
X274878Y-356124D01*
X274441Y-354375D01*
X273568Y-353208D01*
X272039Y-352333D01*
X266144D01*
Y-369833D01*
X273349D01*
X274878Y-368667D01*
X275751Y-366916D01*
X276188Y-364875D01*
X275751Y-362833D01*
X274441Y-361083D01*
X272912Y-360500D01*
X266144D01*
G01X282116Y-375666D02*
X295216D01*
G01X301144Y-369833D02*
Y-352333D01*
X311188Y-369833D01*
Y-352333D01*
G01X323666Y-369833D02*
X321919Y-369541D01*
X320391Y-368375D01*
X319081Y-366625D01*
X318207Y-364583D01*
X317771Y-362250D01*
Y-359916D01*
X318207Y-357583D01*
X319081Y-355541D01*
X320391Y-353792D01*
X321919Y-352625D01*
X323666Y-352333D01*
X325412Y-352625D01*
X326941Y-353792D01*
X328251Y-355541D01*
X329125Y-357583D01*
X329561Y-359916D01*
Y-362250D01*
X329125Y-364583D01*
X328251Y-366625D01*
X326941Y-368375D01*
X325412Y-369541D01*
X323666Y-369833D01*
G01X374507Y-352333D02*
X379966Y-369833D01*
X385425Y-352333D01*
G01X401833Y-369833D02*
X393099D01*
Y-352333D01*
X401833D01*
G01X398339Y-360791D02*
X393099D01*
G01X410599Y-369833D02*
Y-352333D01*
X416058D01*
X417804Y-353208D01*
X418896Y-354375D01*
X419333Y-356708D01*
X418896Y-359042D01*
X417586Y-360500D01*
X416058Y-361375D01*
X410599D01*
G01X416058D02*
X419333Y-369833D01*
G01X432466Y-370416D02*
X432029Y-370125D01*
Y-369541D01*
X432466Y-369250D01*
X432903Y-369541D01*
Y-370125D01*
X432466Y-370416D01*
G01X392881Y-412500D02*
X394628Y-413958D01*
X396593Y-414833D01*
X398339D01*
X400086Y-413958D01*
X401396Y-412500D01*
X402051Y-410458D01*
X401614Y-408417D01*
X400523Y-406666D01*
X398558Y-405500D01*
X395938Y-404916D01*
X394409Y-403750D01*
X393754Y-401708D01*
X394191Y-399666D01*
X395283Y-398208D01*
X396811Y-397333D01*
X398339D01*
X399868Y-397916D01*
X401178Y-399375D01*
G01X410163Y-414833D02*
Y-397333D01*
X414529D01*
X416276Y-398208D01*
X417586Y-399375D01*
X418678Y-401124D01*
X419551Y-403167D01*
X419769Y-406083D01*
X419551Y-409000D01*
X418678Y-411042D01*
X417586Y-412792D01*
X416276Y-413958D01*
X414529Y-414833D01*
X410163D01*
G01X508049Y-352333D02*
Y-369833D01*
X516783D01*
G01X533846D02*
Y-358167D01*
G01Y-360208D02*
X532973Y-359042D01*
X531662Y-358458D01*
X530134Y-358167D01*
X528606Y-358750D01*
X527296Y-359916D01*
X526422Y-361666D01*
X525986Y-364000D01*
X526422Y-366333D01*
X527296Y-368083D01*
X528606Y-369250D01*
X530134Y-369833D01*
X531662Y-369541D01*
X532973Y-368667D01*
X533846Y-367500D01*
G01X542831Y-375083D02*
X544141Y-375666D01*
X545888Y-375083D01*
X546979Y-373917D01*
X547853Y-372458D01*
X549162Y-367792D01*
X552001Y-358167D01*
G01X545014D02*
X549162Y-367792D01*
G01X561641Y-361958D02*
X568628D01*
X567973Y-359916D01*
X566881Y-358750D01*
X565353Y-358167D01*
X563824Y-358458D01*
X562514Y-359333D01*
X561641Y-361375D01*
X561204Y-363125D01*
Y-364875D01*
X561641Y-366625D01*
X562733Y-368375D01*
X564043Y-369541D01*
X565571Y-369833D01*
X567099Y-369250D01*
X568628Y-367500D01*
G01X579359Y-369833D02*
Y-358167D01*
G01Y-360500D02*
X580451Y-359333D01*
X581543Y-358458D01*
X583071Y-358167D01*
X584162Y-358458D01*
X585473Y-359333D01*
G01X560533Y-397333D02*
Y-414833D01*
X551799D01*
G01X536046D02*
Y-397333D01*
X544125Y-409875D01*
X533207D01*
G01X672466Y-414833D02*
X670719Y-414541D01*
X669191Y-413375D01*
X667881Y-411625D01*
X667007Y-409583D01*
X666571Y-407250D01*
Y-404916D01*
X667007Y-402583D01*
X667881Y-400541D01*
X669191Y-398792D01*
X670719Y-397625D01*
X672466Y-397333D01*
X674212Y-397625D01*
X675741Y-398792D01*
X677051Y-400541D01*
X677925Y-402583D01*
X678361Y-404916D01*
Y-407250D01*
X677925Y-409583D01*
X677051Y-411625D01*
X675741Y-413375D01*
X674212Y-414541D01*
X672466Y-414833D01*
G01X674212Y-410166D02*
X676833Y-414833D01*
G01X685163Y-397333D02*
Y-409875D01*
X686036Y-412500D01*
X687783Y-414250D01*
X689966Y-414833D01*
X692149Y-414250D01*
X693896Y-412500D01*
X694769Y-409875D01*
Y-397333D01*
G01X704846D02*
X710086D01*
G01X707466D02*
Y-414833D01*
G01X704846D02*
X710086D01*
G01X719944D02*
Y-397333D01*
X729988Y-414833D01*
Y-397333D01*
G01X747269Y-398792D02*
X745959Y-397916D01*
X744431Y-397333D01*
X742684D01*
X740719Y-398208D01*
X739191Y-399666D01*
X738099Y-401417D01*
X737226Y-404333D01*
X737007Y-406958D01*
X737444Y-409583D01*
X738099Y-411333D01*
X739409Y-413083D01*
X740938Y-414250D01*
X742466Y-414833D01*
X743994D01*
X745523Y-414250D01*
X746833Y-413375D01*
X747925Y-412209D01*
G01X759966Y-414833D02*
Y-406958D01*
X755599Y-397333D01*
G01X764333D02*
X759966Y-406958D01*
G01X650163Y-369833D02*
Y-352333D01*
X654529D01*
X656276Y-353208D01*
X657586Y-354375D01*
X658678Y-356124D01*
X659551Y-358167D01*
X659769Y-361083D01*
X659551Y-364000D01*
X658678Y-366042D01*
X657586Y-367792D01*
X656276Y-368958D01*
X654529Y-369833D01*
X650163D01*
G01X669191Y-361958D02*
X676178D01*
X675523Y-359916D01*
X674431Y-358750D01*
X672903Y-358167D01*
X671374Y-358458D01*
X670064Y-359333D01*
X669191Y-361375D01*
X668754Y-363125D01*
Y-364875D01*
X669191Y-366625D01*
X670283Y-368375D01*
X671593Y-369541D01*
X673121Y-369833D01*
X674649Y-369250D01*
X676178Y-367500D01*
G01X686691Y-367792D02*
X687783Y-368958D01*
X689311Y-369833D01*
X690621D01*
X691931Y-369250D01*
X692804Y-368375D01*
X693241Y-367209D01*
X693023Y-365458D01*
X692149Y-364583D01*
X688219Y-362833D01*
X687346Y-360791D01*
X687783Y-359333D01*
X688656Y-358458D01*
X689966Y-358167D01*
X691276Y-358458D01*
X692586Y-359333D01*
G01X707466Y-358167D02*
Y-369833D01*
G01Y-353500D02*
X707029Y-353208D01*
Y-352625D01*
X707466Y-352333D01*
X707903Y-352625D01*
Y-353208D01*
X707466Y-353500D01*
G01X721909Y-374208D02*
X723438Y-375375D01*
X725184Y-375666D01*
X726712Y-375375D01*
X728023Y-373917D01*
X728896Y-371875D01*
Y-358167D01*
G01Y-360500D02*
X728023Y-359333D01*
X726712Y-358458D01*
X725184Y-358167D01*
X723438Y-358750D01*
X722346Y-359916D01*
X721472Y-361958D01*
X721036Y-364000D01*
X721254Y-365750D01*
X722128Y-367792D01*
X723438Y-369250D01*
X725184Y-369833D01*
X726494Y-369541D01*
X728023Y-368375D01*
X728896Y-367209D01*
G01X738754Y-369833D02*
Y-358167D01*
G01Y-361083D02*
X739628Y-359625D01*
X740938Y-358458D01*
X742684Y-358167D01*
X744212Y-358458D01*
X745523Y-359625D01*
X746178Y-361666D01*
Y-369833D01*
G01X756691Y-361958D02*
X763678D01*
X763023Y-359916D01*
X761931Y-358750D01*
X760403Y-358167D01*
X758874Y-358458D01*
X757564Y-359333D01*
X756691Y-361375D01*
X756254Y-363125D01*
Y-364875D01*
X756691Y-366625D01*
X757783Y-368375D01*
X759093Y-369541D01*
X760621Y-369833D01*
X762149Y-369250D01*
X763678Y-367500D01*
G01X774409Y-369833D02*
Y-358167D01*
G01Y-360500D02*
X775501Y-359333D01*
X776593Y-358458D01*
X778121Y-358167D01*
X779212Y-358458D01*
X780523Y-359333D01*
G01X821166Y-397333D02*
X819419Y-397916D01*
X818109Y-399375D01*
X817236Y-401124D01*
X816581Y-403458D01*
X816363Y-406083D01*
X816581Y-408708D01*
X817236Y-411042D01*
X818109Y-412792D01*
X819419Y-414250D01*
X821166Y-414833D01*
X822912Y-414250D01*
X824223Y-412792D01*
X825096Y-411042D01*
X825751Y-408708D01*
X825969Y-406083D01*
X825751Y-403458D01*
X825096Y-401124D01*
X824223Y-399375D01*
X822912Y-397916D01*
X821166Y-397333D01*
G01X833863Y-411333D02*
X835172Y-413375D01*
X836919Y-414541D01*
X838884Y-414833D01*
X840631Y-414541D01*
X842378Y-413083D01*
X843469Y-411333D01*
X843688Y-409583D01*
X843251Y-407542D01*
X841723Y-406083D01*
X840194Y-405500D01*
X838229D01*
G01X840194D02*
X841504Y-404625D01*
X842596Y-403167D01*
X843033Y-401417D01*
X842596Y-399666D01*
X841504Y-398208D01*
X839539Y-397333D01*
X837574Y-397625D01*
X835609Y-398792D01*
G01X852236Y-415416D02*
X860096Y-397333D01*
G01X869518Y-400250D02*
X870828Y-398500D01*
X872356Y-397625D01*
X874103Y-397333D01*
X876286Y-397916D01*
X877814Y-399375D01*
X878251Y-401124D01*
X878033Y-402875D01*
X877159Y-404333D01*
X872793Y-407250D01*
X870828Y-409291D01*
X869518Y-412209D01*
X869081Y-414833D01*
X878251D01*
G01X887454Y-412792D02*
X888983Y-414250D01*
X890729Y-414833D01*
X892476Y-414250D01*
X894004Y-412500D01*
X895096Y-409875D01*
X895533Y-407250D01*
Y-404042D01*
X895096Y-401417D01*
X894004Y-399083D01*
X892694Y-397916D01*
X891166Y-397333D01*
X889419Y-397916D01*
X888109Y-399083D01*
X887236Y-400833D01*
X886799Y-403167D01*
X887236Y-405208D01*
X888328Y-407250D01*
X889638Y-408417D01*
X891166Y-408708D01*
X892912Y-408125D01*
X894223Y-406666D01*
X895533Y-404042D01*
G01X904736Y-415416D02*
X912596Y-397333D01*
G01X922018Y-400250D02*
X923328Y-398500D01*
X924856Y-397625D01*
X926603Y-397333D01*
X928786Y-397916D01*
X930314Y-399375D01*
X930751Y-401124D01*
X930533Y-402875D01*
X929659Y-404333D01*
X925293Y-407250D01*
X923328Y-409291D01*
X922018Y-412209D01*
X921581Y-414833D01*
X930751D01*
G01X943666Y-397333D02*
X941919Y-397916D01*
X940609Y-399375D01*
X939736Y-401124D01*
X939081Y-403458D01*
X938863Y-406083D01*
X939081Y-408708D01*
X939736Y-411042D01*
X940609Y-412792D01*
X941919Y-414250D01*
X943666Y-414833D01*
X945412Y-414250D01*
X946723Y-412792D01*
X947596Y-411042D01*
X948251Y-408708D01*
X948469Y-406083D01*
X948251Y-403458D01*
X947596Y-401124D01*
X946723Y-399375D01*
X945412Y-397916D01*
X943666Y-397333D01*
G01X961166Y-414833D02*
Y-397333D01*
X958546Y-400833D01*
G01Y-414833D02*
X963786D01*
G01X978229D02*
X978666Y-411042D01*
X979321Y-407833D01*
X980194Y-404916D01*
X981286Y-401708D01*
X983033Y-397333D01*
X974299D01*
G01X868863Y-369833D02*
Y-352333D01*
X873229D01*
X874976Y-353208D01*
X876286Y-354375D01*
X877378Y-356124D01*
X878251Y-358167D01*
X878469Y-361083D01*
X878251Y-364000D01*
X877378Y-366042D01*
X876286Y-367792D01*
X874976Y-368958D01*
X873229Y-369833D01*
X868863D01*
G01X895096D02*
Y-358167D01*
G01Y-360208D02*
X894223Y-359042D01*
X892912Y-358458D01*
X891384Y-358167D01*
X889856Y-358750D01*
X888546Y-359916D01*
X887672Y-361666D01*
X887236Y-364000D01*
X887672Y-366333D01*
X888546Y-368083D01*
X889856Y-369250D01*
X891384Y-369833D01*
X892912Y-369541D01*
X894223Y-368667D01*
X895096Y-367500D01*
G01X908666Y-352333D02*
Y-369833D01*
G01X905609Y-358167D02*
X911723D01*
G01X922891Y-361958D02*
X929878D01*
X929223Y-359916D01*
X928131Y-358750D01*
X926603Y-358167D01*
X925074Y-358458D01*
X923764Y-359333D01*
X922891Y-361375D01*
X922454Y-363125D01*
Y-364875D01*
X922891Y-366625D01*
X923983Y-368375D01*
X925293Y-369541D01*
X926821Y-369833D01*
X928349Y-369250D01*
X929878Y-367500D01*
G54D12*
X6000Y-17500D03*
X16090Y-6960D03*
Y-3360D03*
X4100Y12300D03*
X4300Y38700D03*
X21000Y53500D03*
X4629Y64843D03*
X16090Y240D03*
X63938Y11580D03*
X16090Y3840D03*
X70600Y122500D03*
X65600Y128100D03*
X42600Y129000D03*
X22383Y128937D03*
X20200Y116600D03*
X6220Y219509D03*
X51500Y187600D03*
X51400Y195600D03*
X56755Y199384D03*
X26700Y189160D03*
X22598Y150420D03*
X51076Y202657D03*
X51500Y191500D03*
X44100Y154167D03*
X56400Y158800D03*
X5244Y259114D03*
X4333Y242011D03*
X55200Y285022D03*
X98000Y68200D03*
X112900Y51800D03*
X102000Y62400D03*
X134800Y60300D03*
X135800Y70800D03*
X140100Y14000D03*
X78838Y11602D03*
X124300Y99500D03*
X97600Y92200D03*
X94193Y99637D03*
X81634Y111544D03*
X76100Y117800D03*
X87600Y106400D03*
X101600Y99700D03*
X135900Y99400D03*
X146700Y108400D03*
X217340Y-3360D03*
Y-6960D03*
Y240D03*
Y3840D03*
X168858Y12000D03*
X212287Y39469D03*
X154700Y116500D03*
X190700Y127400D03*
X202783Y128937D03*
X215400Y88900D03*
X186100Y186500D03*
X205848Y199637D03*
X219150Y178000D03*
X222450Y199500D03*
X218700Y193900D03*
X222800Y182000D03*
X199600Y156500D03*
X178747Y288699D03*
X182347Y292152D03*
X199557Y292020D03*
X199521Y288390D03*
X220678Y284412D03*
G54D22*
G01X19763Y92200D02*
X19850Y92113D01*
Y75832D01*
X30088Y65594D01*
Y53812D01*
X39700Y44200D01*
X41800D01*
X48000Y38000D01*
G01X99300Y25700D02*
X99200Y25600D01*
X88700D01*
X58700Y55600D01*
G01X23093Y99967D02*
X23100Y99960D01*
Y76500D01*
X36100Y63500D01*
Y56600D01*
X38000Y54700D01*
Y50100D01*
X41225Y46875D01*
X42150D01*
X42163Y46862D01*
X42922D01*
X42984Y46800D01*
X44200D01*
X53276Y37724D01*
Y22962D01*
X55400Y20838D01*
X71562D01*
X76900Y15500D01*
G01X73838Y12100D02*
X73543D01*
X67980Y17663D01*
X49137D01*
X47075Y19725D01*
Y31475D01*
X50100Y34500D01*
G01X68838Y12300D02*
X66650Y14488D01*
X47821D01*
X47809Y14500D01*
X47500D01*
X43900Y18100D01*
Y37609D01*
X40509Y41000D01*
X39400D01*
G01X36900Y17600D02*
X36898Y17602D01*
Y24600D01*
X36896Y24602D01*
Y37806D01*
X23738Y50964D01*
Y62961D01*
X16616Y70083D01*
X7544D01*
X3781Y73846D01*
Y152368D01*
X9581Y158168D01*
Y160069D01*
G01X26000Y51600D02*
X26913Y52513D01*
Y64278D01*
X17933Y73258D01*
X8860D01*
X6956Y75162D01*
Y150859D01*
X13943Y157846D01*
Y161887D01*
X11612Y164218D01*
Y177464D01*
X11840Y177692D01*
G01X15857Y202417D02*
Y202217D01*
X15856Y202216D01*
Y189688D01*
X23701Y181843D01*
Y154838D01*
X18102Y149239D01*
Y97798D01*
X19763Y96137D01*
Y92200D01*
G01X16253Y180320D02*
X18191Y178382D01*
Y165875D01*
X17851Y165535D01*
Y157263D01*
X11752Y151164D01*
Y84002D01*
X9000Y81250D01*
G01X20539Y163381D02*
Y155460D01*
X14927Y149848D01*
Y83177D01*
X9000Y77250D01*
G01X40900Y88400D02*
Y98487D01*
X44200Y101787D01*
Y109200D01*
X46200Y111200D01*
G01X38189Y220472D02*
X41872Y224155D01*
Y230493D01*
X40595Y231770D01*
X35116D01*
X30487Y227141D01*
X21524D01*
X10506Y216123D01*
Y187470D01*
X16253Y181723D01*
Y180320D01*
G01X38189Y228346D02*
X33148Y223305D01*
Y220626D01*
X30939Y218417D01*
X16584D01*
X13181Y215014D01*
Y188579D01*
X20866Y180894D01*
Y163708D01*
X20539Y163381D01*
G01X9581Y160069D02*
Y161758D01*
X8437Y162902D01*
Y180557D01*
X4156Y184838D01*
Y223718D01*
X25429Y244991D01*
X31212D01*
X38189Y251968D01*
G01X11840Y177692D02*
Y181645D01*
X7331Y186154D01*
Y217439D01*
X20246Y230354D01*
Y233182D01*
X23490Y236426D01*
X30521D01*
X38189Y244094D01*
G01X136439Y31761D02*
X151561D01*
X155200Y35400D01*
X166600D01*
X202860Y71660D01*
X204340D01*
G01X220200Y151000D02*
X226500Y144700D01*
Y30300D01*
X213038Y16838D01*
X139838D01*
X135600Y12600D01*
X129800D01*
X126742Y15658D01*
G01X82200Y60800D02*
X95600D01*
X100100Y56300D01*
G01X125700Y26500D02*
X176400D01*
X208900Y59000D01*
G01X219269Y216635D02*
Y201115D01*
X203589Y185435D01*
X196723D01*
X190283Y178995D01*
Y165258D01*
X186025Y161000D01*
Y118124D01*
X167311Y99410D01*
Y80785D01*
X160800Y74274D01*
Y72000D01*
G01X154444Y72036D02*
Y72409D01*
X164136Y82101D01*
Y100726D01*
X182850Y119440D01*
Y162316D01*
X187108Y166574D01*
Y180311D01*
X195407Y188610D01*
X202273D01*
X216062Y202399D01*
Y232076D01*
X215916Y232222D01*
G01X160794Y86162D02*
Y101875D01*
X177122Y118203D01*
Y186545D01*
X182362Y191785D01*
X200957D01*
X212181Y203009D01*
Y220879D01*
X212713Y221411D01*
Y230567D01*
X207060Y236220D01*
X198426D01*
G01X193500Y135835D02*
Y114800D01*
X190900Y112200D01*
G01X159711Y82091D02*
X157755Y84047D01*
Y103166D01*
X174397Y119808D01*
Y187880D01*
X180977Y194460D01*
X197765D01*
X209506Y206201D01*
Y221988D01*
X210038Y222520D01*
Y229458D01*
X209506Y229990D01*
G01X156891Y79378D02*
X154935Y81334D01*
Y104130D01*
X171722Y120917D01*
Y189673D01*
X179321Y197272D01*
X196793D01*
X206831Y207310D01*
Y223097D01*
X207750Y224016D01*
G01X184900Y106300D02*
X184726D01*
X171263Y92837D01*
G01X198426Y220472D02*
X193280Y225618D01*
Y228552D01*
X196923Y232195D01*
X207301D01*
X209506Y229990D01*
G01X219269Y216635D02*
Y233573D01*
X200874Y251968D01*
X198426D01*
G01Y228346D02*
X203420D01*
X207750Y224016D01*
G01X215916Y232222D02*
X204044Y244094D01*
X198426D01*
G54D13*
G01X-351984Y-328833D02*
X-383984D01*
G01X-351984Y-344833D02*
Y-424833D01*
G01D02*
X998716D01*
G01X-355984Y-328833D02*
G02I-12000J0D01*
G01X-361134D02*
G02I-6850J0D01*
G01X-367984Y-344833D02*
Y-312833D01*
G01X-351984Y-344833D02*
X998716D01*
G01X-351984Y-380333D02*
X998716D01*
G01X24409Y204271D02*
Y211023D01*
G01X17657D02*
X24409D01*
G01D02*
X31161D01*
G01X40157Y204271D02*
Y211023D01*
G01X33405D02*
X40157D01*
G01D02*
X46909D01*
G01X42126Y299147D02*
Y303149D01*
G01X24409Y254665D02*
Y261417D01*
G01D02*
Y268169D01*
G01X17657Y261417D02*
X24409D01*
G01D02*
X31161D01*
G01X40157D02*
Y268169D01*
G01X33405Y261417D02*
X40157D01*
G01D02*
X46909D01*
G01X42126Y303149D02*
Y307151D01*
G01X38124Y303149D02*
X42126D01*
G01D02*
X46128D01*
G01X211216Y-344833D02*
Y-424833D01*
G01X193642Y211023D02*
X200394D01*
G01X195420Y206049D02*
X200394Y211023D01*
G01X184646Y204271D02*
Y211023D01*
G01D02*
Y217775D01*
G01X177894Y211023D02*
X184646D01*
G01D02*
X191398D01*
G01X202363Y299147D02*
Y303149D01*
G01X184646Y254665D02*
Y261417D01*
G01D02*
Y268169D01*
G01X177894Y261417D02*
X184646D01*
G01D02*
X191398D01*
G01X200394D02*
Y268169D01*
G01X193642Y261417D02*
X200394D01*
G01D02*
X207146D01*
G01X202363Y303149D02*
Y307151D01*
G01X198361Y303149D02*
X202363D01*
G01D02*
X206365D01*
G01X348716Y-344833D02*
Y-424833D01*
G01X463716Y-344833D02*
Y-424833D01*
G01X631216Y-344833D02*
Y-424833D01*
G01X801216Y-344833D02*
Y-424833D01*
G01X998716Y-344833D02*
Y-424833D01*
G01X1026716Y-328833D02*
G02I-12000J0D01*
G01X1021566D02*
G02I-6850J0D01*
G01X1014716Y-344833D02*
Y-312833D01*
G01X1030716Y-328833D02*
X998716D01*
X48000Y38000D03*
X58700Y55600D03*
X33200Y59100D03*
X35744Y51944D03*
X41000Y36900D03*
X50100Y20700D03*
X57450Y35400D03*
X55500Y42000D03*
X69446Y48262D03*
X70360Y25750D03*
X73000Y57200D03*
X57400Y26400D03*
X63300Y37300D03*
X43900Y59600D03*
X42300Y51900D03*
X50100Y34500D03*
X68838Y12300D03*
X39400Y41000D03*
X36900Y17600D03*
X26000Y51600D03*
X19763Y92200D03*
X55700Y121400D03*
X22800Y112600D03*
X32100Y114900D03*
X42500Y115000D03*
X47300Y107940D03*
X34900Y106742D03*
X37100Y73960D03*
X37500Y87300D03*
X17700Y89400D03*
X50400Y118300D03*
X24000Y120900D03*
X41492Y106258D03*
X27200Y104100D03*
X33100Y73900D03*
X32200Y91400D03*
X40000Y77100D03*
X23093Y99967D03*
X9000Y81250D03*
Y77250D03*
X40900Y88400D03*
X46200Y111200D03*
X15857Y202417D03*
X47300Y168700D03*
X15007Y163581D03*
X51400Y168300D03*
X16253Y180320D03*
X20539Y163381D03*
X9581Y160069D03*
X11840Y177692D03*
X4100Y294900D03*
X60300Y290000D03*
X17100Y278300D03*
X13650Y278350D03*
X26270Y282547D03*
X22820Y282597D03*
X18600Y338800D03*
X4200Y312100D03*
Y329000D03*
X42800Y338500D03*
X29000Y338600D03*
X60400Y305900D03*
X60500Y316400D03*
X60300Y331800D03*
X60400Y350300D03*
X44000Y350200D03*
X20100Y350300D03*
X4400D03*
X99300Y25700D03*
X136439Y31761D03*
X132500Y41200D03*
X79000Y43600D03*
X75100Y63900D03*
X118100Y45000D03*
X104900Y21400D03*
X114900Y39900D03*
X97200Y44150D03*
X132600Y53800D03*
X119200Y30900D03*
X97500Y36600D03*
X97400Y29300D03*
X132600Y29600D03*
X124300Y22600D03*
X76900Y15500D03*
X73838Y12100D03*
X126742Y15658D03*
X82200Y60800D03*
X100100Y56300D03*
X125700Y26500D03*
X75600Y87000D03*
Y91500D03*
X79750Y76600D03*
X79604Y86869D03*
X219300Y-13900D03*
X208500Y-22000D03*
X204340Y71660D03*
X186200Y14900D03*
X222500Y35100D03*
X208500Y9400D03*
X203300Y14800D03*
X217800Y14300D03*
X169750Y62500D03*
X163452Y32350D03*
X161300Y51500D03*
X174300Y52000D03*
X172800Y44950D03*
X182800Y46500D03*
X220732Y46039D03*
X194560Y53277D03*
X218300Y32700D03*
X222609Y53150D03*
X179093Y38185D03*
X163000Y43800D03*
X179500Y42750D03*
X178843Y59000D03*
X188250Y66000D03*
X207293Y45526D03*
X211900Y24800D03*
X194560Y56777D03*
X160800Y72000D03*
X154444Y72036D03*
X208900Y59000D03*
X160794Y86162D03*
X219000Y104060D03*
X211000Y140500D03*
X174600Y86980D03*
X198100Y104000D03*
X184700Y112500D03*
X218350Y111900D03*
X204818Y118400D03*
X210276Y122000D03*
X192500Y73385D03*
X218700Y132335D03*
X219000Y107560D03*
X214500Y112000D03*
X192691Y84234D03*
X214800Y128309D03*
X193500Y135835D03*
X190900Y112200D03*
X159711Y82091D03*
X156891Y79378D03*
X184900Y106300D03*
X171263Y92837D03*
X214119Y216661D03*
X224000Y210584D03*
X207750Y224016D03*
X220200Y151000D03*
X219269Y216635D03*
X214401Y281884D03*
X215411Y270499D03*
X209506Y229990D03*
X215916Y232222D03*
X222500Y344500D03*
X200200Y343900D03*
X188300Y343400D03*
X193300Y337900D03*
X211900Y337500D03*
X219900Y330500D03*
X214200Y325100D03*
X209500Y350300D03*
X188000D03*
X172300Y337600D03*
Y350200D03*
X220550Y306050D03*
X224000Y306000D03*
X228400Y-21400D03*
X228600Y42000D03*
X228300Y6100D03*
X228400Y22800D03*
X228600Y69200D03*
Y85900D03*
X227800Y322200D03*
X228500Y337100D03*
X228400Y350200D03*
G54D14*
X37283Y173228D03*
X27283D03*
X193583D03*
X183583D03*
G54D15*
X38189Y220472D03*
X28346Y222440D03*
X38189Y251968D03*
Y244094D03*
Y236220D03*
Y228346D03*
X28346Y232283D03*
Y240157D03*
Y250000D03*
X12598Y312992D03*
X51968D03*
X198426Y220472D03*
X188583Y222440D03*
X198426Y251968D03*
Y244094D03*
Y236220D03*
Y228346D03*
X188583Y232283D03*
Y240157D03*
Y250000D03*
X172835Y312992D03*
X212205D03*
G54D16*
X40157Y211023D03*
X24409D03*
X40157Y261417D03*
X24409D03*
X200394Y211023D03*
X184646D03*
X200394Y261417D03*
X184646D03*
G54D17*
X16977Y244294D03*
X16984Y248748D03*
X96200Y16400D03*
X133200Y17751D03*
X107506Y16719D03*
X116430Y16569D03*
X191391Y278906D03*
X195939Y278959D03*
G54D18*
X22440Y303149D03*
X32283D03*
X42126D03*
X22440Y322835D03*
X32283D03*
X42126D03*
X182677Y303149D03*
X192520D03*
X202363D03*
X182677Y322835D03*
X192520D03*
X202363D03*
G54D19*
X116339Y78740D03*
M02*
